FILE_TYPE = CONNECTIVITY;
{Allegro Design Entry HDL 16.6-p007 (v16-6-112F) 10/10/2012}
"PAGE_NUMBER" = 118;
0"NC";
1"P1V05_PCH_STBY_KR_PLL\g";
2"P1V05_PCH_STBY_KR_PLL\g";
3"P3V3_STBY\g";
4"P3V3_STBY\g";
5"GND\g";
6"P3V3_STBY\g";
7"P3V3_STBY\g";
8"GND\g";
9"P3V3_STBY\g";
10"GND\g";
11"GND\g";
12"FM_CPU1_SKTOCC_LVT3_N";
13"RST_BMC_SRST_R_N";
14"FM_CPU0_RC_ERROR_R_N";
15"FM_BATTERY_SENSE_EN_R_N";
16"PECI_PCH";
17"H_PM_SYNC1_GTL_R";
18"FM_PCH_LVC1_THERMTRIP_N";
19"TP_PM_SYNC_GTL";
20"TP_PCH_RSVD54";
21"TP_PCH_RSVD53";
22"KR_P1_OCP_TX_DN";
23"KR_P0_OCP_TX_DN";
24"XTAL_KR_25M_OUT";
25"A_KR1_RBIAS";
26"FM_SLPS4_N";
27"FM_CPU0_SKTOCC_LVT3_N";
28"FM_SLPS3_R_N";
29"XDP_PCH_PWR_DEBUG_N";
30"FM_GBE_LOM_DISABLE_N";
31"FM_PCH_PWRBTN_N";
32"TP_PCH_RSVD45";
33"TP_PCH_RSVD32";
34"TP_PCH_RSVD33";
35"TP_PCH_RSVD34";
36"TP_PCH_RSVD35";
37"TP_PCH_RSVD36";
38"RST_SYSTEM_BTN_BUF_N";
39"H_PM_SYNC_GTL";
40"KR_P0_OCP_RX_C_DP";
41"KR_P1_OCP_RX_C_DP";
42"XDP_ITP_PMODE";
43"XDP_PRDY_N";
44"KR_P1_OCP_TX_DP";
45"KR_P0_OCP_TX_DP";
46"XDP_CPU_PWR_DEBUG_N";
47"FM_10GBE_LOM_DISABLE_N";
48"FM_1GB_LOM_DISABLE_N";
49"TP_PCH_RSVD41";
50"TP_PCH_RSVD42";
51"TP_10GBE_KR1_MON_DP";
52"XDP_PREQ_N";
53"TP_10GBE_KR1_MON_DN";
54"RST_RSMRST_N";
55"TP_PLTRST_CPU_N";
56"RST_BMC_SYSRST_BTN_OUT_B_N";
57"TP_SLP_LAN_N";
58"FM_SLP_SUS_N";
59"PWRGD_SYS_PWROK";
60"PWRGD_PCH_PWROK";
61"IRQ_LVC3_WAKE_N";
62"PWRGD_DSW_PWROK";
63"PWRGD_CPUPWRGD_GTL";
64"TP_10GBE_KR0_MON_DP";
65"TP_PCH_RSVD38";
66"XTAL_KR_25M_IN";
67"TP_10GBE_KR0_MON_DN";
68"XDP_PCH_CPU_TCK0";
69"XDP_TDI";
70"XDP_TDO";
71"XDP_TMS";
72"RST_BMC_SRST_N";
73"FM_BATTERY_SENSE_EN_N";
74"KR_P1_OCP_RX_C_DN";
75"XTAL_KR_25M_IN";
76"XTAL_KR_25M_OUT";
77"XDP_PCH_TCK1";
78"TP_CPU_PCH_TRIGGER_OUT";
79"TP_CPU_PCH_TRIGGER_IN";
80"FM_CPU0_RC_ERROR_N";
81"TP_PCH_GDP8_SUSCLK";
82"FM_BMC_CPLD_MP_RST_N";
83"FM_GBE_LOM_DISABLE_N";
84"PWRGD_PVCCIO_CPU0";
85"XDP_PCH_PWR_DEBUG_N";
86"TP_PCH_RSVD37";
87"A_KR0_RBIAS";
88"KR_P0_OCP_RX_C_DN";
89"XDP_TRST_N";
90"FM_SLPS3_N";
%"P1V05_PCH_STBY_KR_PLL"
"1","(-1000,2025)","0","mstr_symbols","I117";
;
BOM_COST"SB"
ROOM"SB_DECOUPLING"
CDS_LIB"mstr_symbols"
VOLTAGE"1.05V"
BODY_TYPE"PLUMBING"
HDL_POWER"P1V05_PCH_STBY_KR_PLL";
"G\NAC"1;
%"P1V05_PCH_STBY_KR_PLL"
"1","(-7225,2400)","0","mstr_symbols","I118";
;
BOM_COST"SB"
VOLTAGE"1.05V"
CDS_LIB"mstr_symbols"
ROOM"SB_DECOUPLING"
BODY_TYPE"PLUMBING"
HDL_POWER"P1V05_PCH_STBY_KR_PLL";
"G\NAC"2;
%"RES"
"1","(-1675,900)","0","mstr_discrete","I120";
;
CDS_SEC"1"
VALUE"0.0"
LOCATION"R8C24"
TOLERANCE"5%"
PACK_TYPE"0402"
MATERIAL"CHIP"
PART_NUMBER"G21497-005"
WATTAGE"1/16W"
SEC"1"
SEC_TYPE"0402"
BOM_COST"SB"
ROOM"SB"
CDS_LOCATION"R8C24"
CDS_LIB"mstr_discrete";
"B"
$PN"2"48;
"A"
$PN"1"83;
%"RES"
"1","(-1675,675)","0","mstr_discrete","I125";
;
CDS_SEC"1"
MATERIAL"EMPTY"
PART_NUMBER"G21497-005"
PACK_TYPE"0402"
LOCATION"R8C23"
TOLERANCE"5%"
VALUE"0.0"
WATTAGE"1/16W"
ROOM"SB"
BOM_COST"SB"
SEC_TYPE"0402"
SEC"1"
CDS_LOCATION"R8C23"
CDS_LIB"mstr_discrete";
"B"
$PN"2"47;
"A"
$PN"1"83;
%"RES"
"2","(-2200,1100)","0","mstr_discrete","I128";
;
CDS_SEC"1"
PART_NUMBER"G21796-016"
PACK_TYPE"0402"
MATERIAL"CHIP"
WATTAGE"1/16W"
TOLERANCE"1%"
LOCATION"R2N6"
VALUE"10.0K"
SEC"1"
SEC_TYPE"0402"
CDS_LOCATION"R2N6"
CDS_LIB"mstr_discrete"
ROOM"SB"
BOM_COST"SB";
"A"
$PN"1"3;
"B"
$PN"2"83;
%"P3V3_STBY"
"1","(-2200,1275)","0","mstr_symbols","I129";
;
SIZE"1B"
CDS_LIB"mstr_symbols"
VOLTAGE"3.3V"
BODY_TYPE"PLUMBING"
HDL_POWER"P3V3_STBY";
"G\NAC"3;
%"RES"
"1","(-6625,3975)","0","mstr_discrete","I131";
;
CDS_SEC"1"
POP"NOPOP"
MATERIAL"CHIP"
LOCATION"R7D23"
VALUE"0.0"
TOLERANCE"5%"
WATTAGE"1/16W"
PART_NUMBER"G21497-005"
PACK_TYPE"0402"
SEC"1"
SEC_TYPE"0402"
BOM_COST"SB"
ROOM"SB"
CDS_LIB"mstr_discrete"
CDS_LOCATION"R7D23";
"B"
$PN"2"13;
"A"
$PN"1"72;
%"P3V3_STBY"
"1","(-5200,625)","0","mstr_symbols","I135";
;
SIZE"1B"
CDS_LIB"mstr_symbols"
VOLTAGE"3.3V"
BODY_TYPE"PLUMBING"
HDL_POWER"P3V3_STBY";
"G\NAC"4;
%"CAP_A"
"1","(-5200,375)","0","dev_discrete","I136";
;
PART_NUMBER"A36096-030"
TOLERANCE"10%"
PACK_TYPE"0402V"
VOLTAGE"16V"
MATERIAL"X7R"
LOCATION"C7D1"
VALUE"0.1UF"
ROOM"SB"
BOM_COST"SB"
CDS_SEC"1"
SEC"1"
SEC_TYPE"0402V"
CDS_LOCATION"C7D1"
CDS_LIB"dev_discrete";
"B"
$PN"2"5;
"A"
$PN"1"4;
%"GND"
"1","(-5200,125)","0","mstr_symbols","I137";
;
VOLTAGE"0.0V"
CDS_LIB"mstr_symbols"
SIZE"1B"
BODY_TYPE"PLUMBING"
HDL_POWER"GND";
"A\NAC"5;
%"74CBTLV1G125"
"1","(-4575,1075)","0","mstr_ttl","I142";
;
POWER_GROUP"VCC=P3V3_STBY;GND=GND;"
LOCATION"U7D1"
MATERIAL"IC"
PART_NUMBER"C88177-001"
PACK_TYPE"SMLF"
$SEC"1"
CDS_SEC"1"
CDS_LIB"mstr_ttl"
CDS_LOCATION"U7D1"
BOM_COST"DEBUG"
ROOM"DEBUG";
"OE_N \B"
$PN"1"84;
"B"
$PN"4"46;
"A"
$PN"2"85;
%"RES"
"2","(-5175,1275)","0","mstr_discrete","I144";
;
CDS_SEC"1"
LOCATION"R7C23"
VALUE"10.0K"
TOLERANCE"1%"
PACK_TYPE"0402"
MATERIAL"CHIP"
WATTAGE"1/16W"
PART_NUMBER"G21796-016"
SEC_TYPE"0402"
SEC"1"
CDS_LOCATION"R7C23"
CDS_LIB"mstr_discrete"
ROOM"SB"
BOM_COST"SB";
"A"
$PN"1"6;
"B"
$PN"2"85;
%"P3V3_STBY"
"1","(-5175,1450)","0","mstr_symbols","I145";
;
CDS_LIB"mstr_symbols"
SIZE"1B"
VOLTAGE"3.3V"
BODY_TYPE"PLUMBING"
HDL_POWER"P3V3_STBY";
"G\NAC"6;
%"RES"
"1","(-6650,4075)","0","mstr_discrete","I167";
;
CDS_SEC"1"
PACK_TYPE"0402"
PART_NUMBER"G21497-005"
TOLERANCE"5%"
VALUE"0.0"
LOCATION"R7W1"
WATTAGE"1/16W"
MATERIAL"CHIP"
SEC"1"
CDS_LOCATION"R7W1"
CDS_LIB"mstr_discrete"
ROOM"SB"
BOM_COST"SB"
SEC_TYPE"0402";
"B"
$PN"2"28;
"A"
$PN"1"90;
%"RES"
"1","(-2725,3650)","0","mstr_discrete","I168";
;
CDS_SEC"1"
TOLERANCE"5%"
VALUE"0.0"
LOCATION"R1W30"
MATERIAL"EMPTY"
WATTAGE"1/16W"
PACK_TYPE"0402"
PART_NUMBER"G21497-005"
SEC"1"
SEC_TYPE"0402"
CDS_LIB"mstr_discrete"
ROOM"NV_DIMM"
BOM_COST"MEM_NV"
CDS_LOCATION"R1W30";
"B"
$PN"2"38;
"A"
$PN"1"56;
%"RES"
"1","(-6650,4225)","0","mstr_discrete","I176";
;
CDS_SEC"1"
TOLERANCE"5%"
PART_NUMBER"G21497-005"
PACK_TYPE"0402"
LOCATION"R7W6"
VALUE"0.0"
MATERIAL"CHIP"
WATTAGE"1/16W"
POP"NOPOP"
CDS_LOCATION"R7W6"
SEC_TYPE"0402"
BOM_COST"SB"
ROOM"SB"
CDS_LIB"mstr_discrete"
SEC"1";
"B"
$PN"2"15;
"A"
$PN"1"73;
%"RES"
"1","(-6650,4375)","0","mstr_discrete","I177";
;
CDS_SEC"1"
POP"NOPOP"
VALUE"0.0"
WATTAGE"1/16W"
TOLERANCE"5%"
LOCATION"R7W9"
PACK_TYPE"0402"
MATERIAL"CHIP"
PART_NUMBER"G21497-005"
SEC"1"
CDS_LIB"mstr_discrete"
ROOM"SB"
BOM_COST"SB"
SEC_TYPE"0402"
CDS_LOCATION"R7W9";
"B"
$PN"2"14;
"A"
$PN"1"80;
%"CAP"
"1","(-7700,600)","0","mstr_discrete","I178";
;
CDS_SEC"1"
CDS_LOCATION"C8C1"
MATERIAL"COG"
PACK_TYPE"0402LF"
TOLERANCE"5%"
VOLTAGE"50V"
LOCATION"C8C1"
VALUE"33.0PF"
PART_NUMBER"A36095-031"
SEC"1"
SEC_TYPE"0402LF"
CDS_LIB"mstr_discrete";
"A"
$PN"1"75;
"B"
$PN"2"11;
%"CAP"
"1","(-7250,600)","0","mstr_discrete","I179";
;
CDS_SEC"1"
CDS_LOCATION"C8C2"
MATERIAL"COG"
PART_NUMBER"A36095-031"
PACK_TYPE"0402LF"
VOLTAGE"50V"
VALUE"33.0PF"
LOCATION"C8C2"
TOLERANCE"5%"
SEC"1"
SEC_TYPE"0402LF"
CDS_LIB"mstr_discrete";
"A"
$PN"1"76;
"B"
$PN"2"10;
%"RES"
"2","(-6450,4600)","0","mstr_discrete","I180";
;
CDS_SEC"1"
TOLERANCE"1%"
WATTAGE"1/16W"
PACK_TYPE"0402"
MATERIAL"CHIP"
PART_NUMBER"G21796-072"
VALUE"4.75K"
LOCATION"R7W19"
CDS_LOCATION"R7W19"
CDS_LIB"mstr_discrete"
SEC_TYPE"0402"
SEC"1"
ROOM"CPU0";
"A"
$PN"1"7;
"B"
$PN"2"15;
%"P3V3_STBY"
"1","(-6450,4900)","0","mstr_symbols","I181";
;
HDL_POWER"P3V3_STBY"
BODY_TYPE"PLUMBING"
SIZE"1B"
CDS_LIB"mstr_symbols"
VOLTAGE"3.3V";
"G\NAC"7;
%"RES"
"2","(-6200,4600)","0","mstr_discrete","I183";
;
CDS_SEC"1"
LOCATION"R7W21"
PART_NUMBER"G21796-072"
MATERIAL"CHIP"
PACK_TYPE"0402"
WATTAGE"1/16W"
VALUE"4.75K"
TOLERANCE"1%"
ROOM"CPU0"
SEC"1"
SEC_TYPE"0402"
CDS_LIB"mstr_discrete"
CDS_LOCATION"R7W21";
"A"
$PN"1"7;
"B"
$PN"2"13;
%"RES"
"1","(-1575,2675)","0","mstr_discrete","I66";
;
CDS_SEC"1"
TOLERANCE"1%"
LOCATION"R3N9"
PACK_TYPE"0402"
MATERIAL"CHIP"
VALUE"10.0"
WATTAGE"1/16W"
PART_NUMBER"G21796-066"
SEC_TYPE"0402"
BOM_COST"SB"
SEC"1"
ROOM"SB"
CDS_LIB"mstr_discrete"
CDS_LOCATION"R3N9";
"B"
$PN"2"39;
"A"
$PN"1"17;
%"RES"
"2","(-1075,2475)","0","mstr_discrete","I67";
;
CDS_SEC"1"
LOCATION"R3N14"
TOLERANCE"1%"
VALUE"49.9"
WATTAGE"1/16W"
MATERIAL"EMPTY"
PART_NUMBER"G21796-047"
PACK_TYPE"0402"
SEC"1"
BOM_COST"SB"
SEC_TYPE"0402"
ROOM"SB"
CDS_LOCATION"R3N14"
CDS_LIB"mstr_discrete";
"A"
$PN"1"39;
"B"
$PN"2"8;
%"GND"
"1","(-1075,2225)","0","mstr_symbols","I69";
;
SIZE"1B"
VOLTAGE"0.0V"
CDS_LIB"mstr_symbols"
BODY_TYPE"PLUMBING"
HDL_POWER"GND";
"A\NAC"8;
%"RES"
"2","(-2300,4650)","0","mstr_discrete","I71";
;
CDS_SEC"1"
VALUE"4.75K"
LOCATION"R3N13"
TOLERANCE"1%"
WATTAGE"1/16W"
MATERIAL"CHIP"
PACK_TYPE"0402"
PART_NUMBER"G21796-072"
SEC_TYPE"0402"
BOM_COST"SB"
SEC"1"
ROOM"SB"
CDS_LIB"mstr_discrete"
CDS_LOCATION"R3N13";
"A"
$PN"1"9;
"B"
$PN"2"61;
%"P3V3_STBY"
"1","(-2300,4875)","0","mstr_symbols","I72";
;
CDS_LIB"mstr_symbols"
SIZE"1B"
VOLTAGE"3.3V"
BODY_TYPE"PLUMBING"
HDL_POWER"P3V3_STBY";
"G\NAC"9;
%"LBG_CORE_QAT_EXT_D"
"5","(-4025,3025)","0","mstr_u_proc","I73";
;
CDS_SEC"5"
MATERIAL"IC"
PART_NUMBER"H91415-002"
LOCATION"U7C1"
CDS_LIB"mstr_u_proc"
BOM_COST"SB"
ROOM"SB"
PACK_TYPE"BGA1"
SEC_TYPE"BGA1"
SEC"5"
CDS_LOCATION"U7C1";
"WAKE_N"
$PN"K9"61;
"TRIGGER_OUT"
$PN"R13"78;
"TRIGGER_IN"
$PN"M7"79;
"THRMTRIP_N"
$PN"V15"18;
"SYS_RESET_N"
$PN"BV19"56;
"SYS_PWROK"
$PN"BY19"59;
"SLP_SUS_N"
$PN"P7"58;
"SLP_GBE_N"
$PN"M15"57;
"RSVD<32>"
$PN"AA54"33;
"RSVD<33>"
$PN"V56"34;
"RSVD<34>"
$PN"Y56"35;
"RSVD<35>"
$PN"W54"36;
"RSVD<36>"
$PN"AK54"37;
"RSVD<37>"
$PN"BN29"86;
"RSVD<38>"
$PN"BL29"65;
"RSVD<39>"
$PN"BL26"67;
"RSVD<40>"
$PN"BN26"64;
"RSVD<41>"
$PN"BJ40"49;
"RSVD<42>"
$PN"BG40"50;
"RSVD<43>"
$PN"BL33"53;
"RSVD<44>"
$PN"BN33"51;
"RSVD<45>"
$PN"P22"32;
"RSVD<53>"
$PN"P26"21;
"RSVD<54>"
$PN"R24"20;
"RSMRST_N"
$PN"P15"54;
"PROC_PWRGD"
$PN"R9"63;
"PREQ_N"
$PN"U54"52;
"PRDY_N"
$PN"AD54"43;
"PM_SYNC2"
$PN"V7"19;
"PM_SYNC"
$PN"U13"17;
"PLTRST_CPU_N"
$PN"U17"55;
"PECI"
$PN"U9"16;
"PCH_PWROK"
$PN"R17"60;
"LAN_XTAL_OUT"
$PN"BY16"24;
"LAN_XTAL_IN"
$PN"BV16"66;
"LAN_TX_P3P"
$PN"BM31"0;
"LAN_TX_P3N"
$PN"BR31"0;
"LAN_TX_P2P"
$PN"BR35"0;
"LAN_TX_P2N"
$PN"BM35"0;
"LAN_TX_P1P"
$PN"BR24"44;
"LAN_TX_P1N"
$PN"BM24"22;
"LAN_TX_P0P"
$PN"BR27"45;
"LAN_TX_P0N"
$PN"BM27"23;
"LAN_RX_P3P"
$PN"BH35"0;
"LAN_RX_P3N"
$PN"BF35"0;
"LAN_RX_P2P"
$PN"BG37"0;
"LAN_RX_P2N"
$PN"BJ37"0;
"LAN_RX_P1P"
$PN"BJ29"41;
"LAN_RX_P1N"
$PN"BG29"74;
"LAN_RX_P0P"
$PN"BF31"40;
"LAN_RX_P0N"
$PN"BH31"88;
"LAN_RBIAS_1"
$PN"BD42"25;
"LAN_RBIAS_0"
$PN"BB29"87;
"JTAG_TMS"
$PN"AH54"71;
"JTAG_TDO"
$PN"AP56"70;
"JTAG_TDI"
$PN"AN54"69;
"JTAG_TCK"
$PN"AL56"77;
"JTAGX"
$PN"AF54"68;
"ITP_PMODE"
$PN"AR54"42;
"GPD9"
$PN"A15"82;
"GPD8_SUSCLK"
$PN"C13"81;
"GPD7"
$PN"H9"15;
"GPD6_SLP_A_N"
$PN"G11"27;
"GPD5_SLP_S4_N"
$PN"B16"26;
"GPD4_SLP_S3_N"
$PN"D14"28;
"GPD3_PWRBTN_N"
$PN"C15"31;
"GPD2_GBE_WAKE_N"
$PN"M11"13;
"GPD1_ACPRESENT"
$PN"H13"12;
"GPD11_GBEPHY"
$PN"A13"30;
"GPD10_SLP_S5_N"
$PN"B14"14;
"GPD0"
$PN"G15"29;
"DSW_PWROK"
$PN"K13"62;
"CPU_TRST_N"
$PN"AT56"89;
%"CRYSTAL"
"1","(-7400,850)","0","mstr_discrete","I76";
;
CDS_SEC"1"
MATERIAL"IC"
VALUE"25.000MHZ"
LOCATION"Y8C1"
PART_NUMBER"H19611-001"
BOM_COST"SB"
SEC"1"
SEC_TYPE"2013"
ROOM"SB"
CDS_LIB"mstr_discrete"
CDS_LOCATION"Y8C1"
PACK_TYPE"2013";
"B"
$PN"3"76;
"A"
$PN"1"75;
%"GND"
"1","(-7250,400)","0","mstr_symbols","I78";
;
CDS_LIB"mstr_symbols"
SIZE"1B"
VOLTAGE"0.0V"
BODY_TYPE"PLUMBING"
HDL_POWER"GND";
"A\NAC"10;
%"GND"
"1","(-7700,400)","0","mstr_symbols","I80";
;
SIZE"1B"
CDS_LIB"mstr_symbols"
VOLTAGE"0.0V"
BODY_TYPE"PLUMBING"
HDL_POWER"GND";
"A\NAC"11;
%"RES"
"2","(-7225,2175)","0","mstr_discrete","I96";
;
CDS_SEC"1"
MATERIAL"CHIP"
PACK_TYPE"0402"
PART_NUMBER"G85996-004"
WATTAGE"1/16W"
TOLERANCE"0.1%"
VALUE"1.0K"
LOCATION"R2N4"
SEC"1"
SEC_TYPE"0402"
ROOM"SB"
CDS_LOCATION"R2N4"
CDS_LIB"mstr_discrete";
"A"
$PN"1"2;
"B"
$PN"2"87;
%"RES"
"1","(-1700,1875)","0","mstr_discrete","I99";
;
CDS_SEC"1"
MATERIAL"CHIP"
TOLERANCE"0.1%"
PACK_TYPE"0402"
PART_NUMBER"G85996-004"
LOCATION"R2M6"
VALUE"1.0K"
WATTAGE"1/16W"
SEC"1"
SEC_TYPE"0402"
ROOM"SB"
CDS_LIB"mstr_discrete"
CDS_LOCATION"R2M6";
"B"
$PN"2"1;
"A"
$PN"1"25;
END.
